(kicad_pcb
	(version 20260206)
	(generator "pcbnew")
	(generator_version "10.0")
	(general
		(thickness 1.6)
		(legacy_teardrops no)
	)
	(paper "A4")
	(title_block
		(title "timecard-production-celestica-r4006 — R4006-B0001-02_R01.brd")
		(comment 1 "Time Appliance Project (Time Card) / footprints 837-841 of 1113")
	)
	(layers
		(0 "F.Cu" signal "TOP")
		(4 "In1.Cu" signal "L02_GND1")
		(6 "In2.Cu" signal "L03_SIG1")
		(8 "In3.Cu" signal "L04_GND2")
		(10 "In4.Cu" signal "L05_VCC1")
		(12 "In5.Cu" signal "L06_VCC2")
		(14 "In6.Cu" signal "L07_GND3")
		(16 "In7.Cu" signal "L08_SIG2")
		(18 "In8.Cu" signal "L09_GND4")
		(2 "B.Cu" signal "BOTTOM")
		(9 "F.Adhes" user "F.Adhesive")
		(11 "B.Adhes" user "B.Adhesive")
		(13 "F.Paste" user "Package Geometry/Pastemask Top")
		(15 "B.Paste" user "Package Geometry/Pastemask Bottom")
		(5 "F.SilkS" user "Ref Des/Silkscreen Top")
		(7 "B.SilkS" user "Ref Des/Silkscreen Bottom")
		(1 "F.Mask" user "Board Geometry/Soldermask Top")
		(3 "B.Mask" user "Board Geometry/Soldermask Bottom")
		(17 "Dwgs.User" user "User.Drawings")
		(19 "Cmts.User" user "User.Comments")
		(21 "Eco1.User" user "User.Eco1")
		(23 "Eco2.User" user "User.Eco2")
		(25 "Edge.Cuts" user "Board Geometry/Outline")
		(27 "Margin" user)
		(31 "F.CrtYd" user "Package Geometry/Place Bound Top")
		(29 "B.CrtYd" user "Package Geometry/Place Bound Bottom")
		(35 "F.Fab" user "Ref Des/Assembly Top")
		(33 "B.Fab" user "Ref Des/Assembly Bottom")
	)
	(footprint ""
		(layer "B.Cu")
		(at 139.5476 -81.4324)
		(property "Reference" "C303"
			(at 0.6604 -7.68223 0)
			(unlocked yes)
			(layer "B.SilkS")
			(effects
				(font
					(size 0.7874 0.5842)
					(thickness 0.1524)
				)
				(justify mirror)
			)
		)
		(property "Value" "VAL*"
			(at -0.0762 3.134106 0)
			(unlocked yes)
			(layer "B.Fab")
			(hide yes)
			(effects
				(font
					(size 0.7874 0.5842)
					(thickness 0.1524)
				)
				(justify mirror)
			)
		)
		(property "Device Type" "CAPACITOR-G107-0F106-EM,10UF,2A"
			(at -0.0508 2.194306 0)
			(unlocked yes)
			(layer "B.Fab")
			(hide yes)
			(effects
				(font
					(size 0.7874 0.5842)
					(thickness 0.1524)
				)
				(justify mirror)
			)
		)
		(property "User Part Number" "PARTNUM*"
			(at -0.1016 5.013706 0)
			(unlocked yes)
			(layer "Cmts.User")
			(hide yes)
			(effects
				(font
					(size 0.7874 0.5842)
					(thickness 0.1524)
				)
				(justify mirror)
			)
		)
		(property "Tolerance" "TOL*"
			(at -0.0762 4.048506 0)
			(unlocked yes)
			(layer "Cmts.User")
			(hide yes)
			(effects
				(font
					(size 0.7874 0.5842)
					(thickness 0.1524)
				)
				(justify mirror)
			)
		)
		(duplicate_pad_numbers_are_jumpers no)
		(fp_line
			(start -1.5748 -0.9398)
			(end 1.5748 -0.9398)
			(stroke
				(width 0.1)
				(type default)
			)
			(layer "B.SilkS")
		)
		(fp_line
			(start -1.5748 0.9398)
			(end -1.5748 -0.9398)
			(stroke
				(width 0.1)
				(type default)
			)
			(layer "B.SilkS")
		)
		(fp_line
			(start 1.5748 -0.9398)
			(end 1.5748 0.9398)
			(stroke
				(width 0.1)
				(type default)
			)
			(layer "B.SilkS")
		)
		(fp_line
			(start 1.5748 0.9398)
			(end -1.5748 0.9398)
			(stroke
				(width 0.1)
				(type default)
			)
			(layer "B.SilkS")
		)
		(fp_rect
			(start 1.5748 0.9398)
			(end -1.5748 -0.9398)
			(stroke
				(width 0)
				(type default)
			)
			(fill no)
			(layer "B.CrtYd")
		)
		(fp_line
			(start -1.016 -0.635)
			(end 1.016 -0.635)
			(stroke
				(width 0.1)
				(type default)
			)
			(layer "B.Fab")
		)
		(fp_line
			(start -1.016 0.635)
			(end -1.016 -0.635)
			(stroke
				(width 0.1)
				(type default)
			)
			(layer "B.Fab")
		)
		(fp_line
			(start 1.016 -0.635)
			(end 1.016 0.635)
			(stroke
				(width 0.1)
				(type default)
			)
			(layer "B.Fab")
		)
		(fp_line
			(start 1.016 0.635)
			(end -1.016 0.635)
			(stroke
				(width 0.1)
				(type default)
			)
			(layer "B.Fab")
		)
		(pad "1" smd rect
			(at 0.8382 0 180)
			(size 0.9652 1.3716)
			(layers "B.Cu" "B.Mask" "B.Paste")
			(net "XP12R0V_IN")
		)
		(pad "2" smd rect
			(at -0.8382 0 180)
			(size 0.9652 1.3716)
			(layers "B.Cu" "B.Mask" "B.Paste")
			(net "SG")
		)
		(zone
			(layer "B.Cu")
			(hatch none 0.5)
			(connect_pads
				(clearance 0)
			)
			(min_thickness 0.25)
			(keepout
				(tracks allowed)
				(vias not_allowed)
				(pads allowed)
				(copperpour not_allowed)
				(footprints allowed)
			)
			(placement
				(enabled no)
				(sheetname "")
			)
			(fill
				(thermal_gap 0.5)
				(thermal_bridge_width 0.5)
				(island_removal_mode 0)
			)
			(polygon
				(pts
					(xy 139.7762 -80.7974) (xy 139.7762 -82.0674) (xy 139.319 -82.0674) (xy 139.319 -80.7974)
				)
			)
		)
		(zone
			(layer "B.Cu")
			(hatch none 0.5)
			(connect_pads
				(clearance 0)
			)
			(min_thickness 0.25)
			(keepout
				(tracks not_allowed)
				(vias allowed)
				(pads allowed)
				(copperpour not_allowed)
				(footprints allowed)
			)
			(placement
				(enabled no)
				(sheetname "")
			)
			(fill
				(thermal_gap 0.5)
				(thermal_bridge_width 0.5)
				(island_removal_mode 0)
			)
			(polygon
				(pts
					(xy 139.7762 -80.7974) (xy 139.7762 -82.0674) (xy 139.319 -82.0674) (xy 139.319 -80.7974)
				)
			)
		)
	)
	(footprint ""
		(layer "B.Cu")
		(at 113.347246 -41.823132 180)
		(property "Reference" "C147"
			(at 41.909746 -1.250442 0)
			(unlocked yes)
			(layer "B.SilkS")
			(effects
				(font
					(size 0.635 0.4064)
					(thickness 0.1524)
				)
				(justify mirror)
			)
		)
		(property "Value" "VAL*"
			(at 0 3.718306 180)
			(unlocked yes)
			(layer "B.Fab")
			(hide yes)
			(effects
				(font
					(size 0.7874 0.5842)
					(thickness 0.127)
				)
				(justify mirror)
			)
		)
		(property "Device Type" "CAPACITOR-G105-0B104-CK,0.1UF,A"
			(at 0 1.432306 180)
			(unlocked yes)
			(layer "B.Fab")
			(hide yes)
			(effects
				(font
					(size 0.7874 0.5842)
					(thickness 0.127)
				)
				(justify mirror)
			)
		)
		(property "User Part Number" "PARTNUM*"
			(at 0 2.575306 180)
			(unlocked yes)
			(layer "Cmts.User")
			(hide yes)
			(effects
				(font
					(size 0.7874 0.5842)
					(thickness 0.127)
				)
				(justify mirror)
			)
		)
		(property "Tolerance" "TOL*"
			(at 0 4.861306 180)
			(unlocked yes)
			(layer "Cmts.User")
			(hide yes)
			(effects
				(font
					(size 0.7874 0.5842)
					(thickness 0.127)
				)
				(justify mirror)
			)
		)
		(duplicate_pad_numbers_are_jumpers no)
		(fp_line
			(start 0.970026 0.4699)
			(end 0.970026 -0.4699)
			(stroke
				(width 0.1)
				(type default)
			)
			(layer "B.SilkS")
		)
		(fp_line
			(start 0.970026 -0.4699)
			(end -0.970026 -0.4699)
			(stroke
				(width 0.1)
				(type default)
			)
			(layer "B.SilkS")
		)
		(fp_line
			(start -0.970026 0.4699)
			(end 0.970026 0.4699)
			(stroke
				(width 0.1)
				(type default)
			)
			(layer "B.SilkS")
		)
		(fp_line
			(start -0.970026 -0.4699)
			(end -0.970026 0.4699)
			(stroke
				(width 0.1)
				(type default)
			)
			(layer "B.SilkS")
		)
		(fp_poly
			(pts
				(xy 0.970026 0.4699) (xy -0.970026 0.4699) (xy -0.970026 -0.4699) (xy 0.970026 -0.4699)
			)
			(stroke
				(width 0)
				(type default)
			)
			(fill no)
			(layer "B.CrtYd")
		)
		(fp_line
			(start 0.508 0.3048)
			(end 0.508 -0.3048)
			(stroke
				(width 0.1)
				(type default)
			)
			(layer "B.Fab")
		)
		(fp_line
			(start 0.508 -0.3048)
			(end -0.508 -0.3048)
			(stroke
				(width 0.1)
				(type default)
			)
			(layer "B.Fab")
		)
		(fp_line
			(start -0.508 0.3048)
			(end 0.508 0.3048)
			(stroke
				(width 0.1)
				(type default)
			)
			(layer "B.Fab")
		)
		(fp_line
			(start -0.508 -0.3048)
			(end -0.508 0.3048)
			(stroke
				(width 0.1)
				(type default)
			)
			(layer "B.Fab")
		)
		(pad "1" smd circle
			(at 0.500126 0)
			(size 0.635 0.635)
			(layers "B.Cu" "B.Mask" "B.Paste")
			(net "XP1R0V_FPGA_VCCINT")
		)
		(pad "2" smd circle
			(at -0.500126 0)
			(size 0.635 0.635)
			(layers "B.Cu" "B.Mask" "B.Paste")
			(net "SG")
		)
	)
	(footprint ""
		(layer "B.Cu")
		(at 26.289 -79.121 90)
		(property "Reference" "C90"
			(at 0 -1.18237 270)
			(unlocked yes)
			(layer "B.SilkS")
			(effects
				(font
					(size 0.7874 0.5842)
					(thickness 0.1524)
				)
				(justify mirror)
			)
		)
		(property "Value" "VAL*"
			(at -0.02032 2.13233 90)
			(unlocked yes)
			(layer "B.Fab")
			(hide yes)
			(effects
				(font
					(size 0.7874 0.5842)
					(thickness 0.1524)
				)
				(justify mirror)
			)
		)
		(property "Tolerance" "TOL*"
			(at -0.044704 3.05435 90)
			(unlocked yes)
			(layer "Cmts.User")
			(hide yes)
			(effects
				(font
					(size 0.7874 0.5842)
					(thickness 0.1524)
				)
				(justify mirror)
			)
		)
		(property "User Part Number" "PARTNUM*"
			(at -0.02032 4.024884 90)
			(unlocked yes)
			(layer "Cmts.User")
			(hide yes)
			(effects
				(font
					(size 0.7874 0.5842)
					(thickness 0.1524)
				)
				(justify mirror)
			)
		)
		(property "Device Type" "CAPACITOR-G105-0F475-BM,4.7UF,A"
			(at -0.008382 1.210564 90)
			(unlocked yes)
			(layer "B.Fab")
			(hide yes)
			(effects
				(font
					(size 0.7874 0.5842)
					(thickness 0.1524)
				)
				(justify mirror)
			)
		)
		(duplicate_pad_numbers_are_jumpers no)
		(fp_line
			(start 1.143 -0.5588)
			(end 1.143 0.5588)
			(stroke
				(width 0.1)
				(type default)
			)
			(layer "B.SilkS")
		)
		(fp_line
			(start -1.143 -0.5588)
			(end 1.143 -0.5588)
			(stroke
				(width 0.1)
				(type default)
			)
			(layer "B.SilkS")
		)
		(fp_line
			(start 1.143 0.5588)
			(end -1.143 0.5588)
			(stroke
				(width 0.1)
				(type default)
			)
			(layer "B.SilkS")
		)
		(fp_line
			(start -1.143 0.5588)
			(end -1.143 -0.5588)
			(stroke
				(width 0.1)
				(type default)
			)
			(layer "B.SilkS")
		)
		(fp_poly
			(pts
				(xy 1.143 0.5588) (xy -1.143 0.5588) (xy -1.143 -0.5588) (xy 1.143 -0.5588)
			)
			(stroke
				(width 0)
				(type default)
			)
			(fill no)
			(layer "B.CrtYd")
		)
		(fp_line
			(start 0.508 -0.3048)
			(end 0.508 0.3048)
			(stroke
				(width 0.1)
				(type default)
			)
			(layer "B.Fab")
		)
		(fp_line
			(start -0.508 -0.3048)
			(end 0.508 -0.3048)
			(stroke
				(width 0.1)
				(type default)
			)
			(layer "B.Fab")
		)
		(fp_line
			(start 0.508 0.3048)
			(end -0.508 0.3048)
			(stroke
				(width 0.1)
				(type default)
			)
			(layer "B.Fab")
		)
		(fp_line
			(start -0.508 0.3048)
			(end -0.508 -0.3048)
			(stroke
				(width 0.1)
				(type default)
			)
			(layer "B.Fab")
		)
		(pad "1" smd rect
			(at 0.5334 0 270)
			(size 0.7112 0.6096)
			(layers "B.Cu" "B.Mask" "B.Paste")
			(net "FT4232_VREGOUT")
		)
		(pad "2" smd rect
			(at -0.5334 0 270)
			(size 0.7112 0.6096)
			(layers "B.Cu" "B.Mask" "B.Paste")
			(net "SG")
		)
		(zone
			(layer "B.Cu")
			(hatch none 0.5)
			(connect_pads
				(clearance 0)
			)
			(min_thickness 0.25)
			(keepout
				(tracks allowed)
				(vias not_allowed)
				(pads allowed)
				(copperpour not_allowed)
				(footprints allowed)
			)
			(placement
				(enabled no)
				(sheetname "")
			)
			(fill
				(thermal_gap 0.5)
				(thermal_bridge_width 0.5)
				(island_removal_mode 0)
			)
			(polygon
				(pts
					(xy 26.5938 -79.1972) (xy 25.9842 -79.1972) (xy 25.9842 -79.0448) (xy 26.5938 -79.0448)
				)
			)
		)
		(zone
			(layer "B.Cu")
			(hatch none 0.5)
			(connect_pads
				(clearance 0)
			)
			(min_thickness 0.25)
			(keepout
				(tracks not_allowed)
				(vias allowed)
				(pads allowed)
				(copperpour not_allowed)
				(footprints allowed)
			)
			(placement
				(enabled no)
				(sheetname "")
			)
			(fill
				(thermal_gap 0.5)
				(thermal_bridge_width 0.5)
				(island_removal_mode 0)
			)
			(polygon
				(pts
					(xy 26.5938 -79.1972) (xy 25.9842 -79.1972) (xy 25.9842 -79.0448) (xy 26.5938 -79.0448)
				)
			)
		)
	)
	(footprint ""
		(layer "B.Cu")
		(at 104.347264 -40.823134 180)
		(property "Reference" "C111"
			(at 41.400984 -1.251204 0)
			(unlocked yes)
			(layer "B.SilkS")
			(effects
				(font
					(size 0.635 0.4064)
					(thickness 0.1524)
				)
				(justify mirror)
			)
		)
		(property "Value" "VAL*"
			(at 0 3.718306 180)
			(unlocked yes)
			(layer "B.Fab")
			(hide yes)
			(effects
				(font
					(size 0.7874 0.5842)
					(thickness 0.127)
				)
				(justify mirror)
			)
		)
		(property "Tolerance" "TOL*"
			(at 0 4.861306 180)
			(unlocked yes)
			(layer "Cmts.User")
			(hide yes)
			(effects
				(font
					(size 0.7874 0.5842)
					(thickness 0.127)
				)
				(justify mirror)
			)
		)
		(property "User Part Number" "PARTNUM*"
			(at 0 2.575306 180)
			(unlocked yes)
			(layer "Cmts.User")
			(hide yes)
			(effects
				(font
					(size 0.7874 0.5842)
					(thickness 0.127)
				)
				(justify mirror)
			)
		)
		(property "Device Type" "CAPACITOR-G105-0B104-CK,0.1UF,A"
			(at 0 1.432306 180)
			(unlocked yes)
			(layer "B.Fab")
			(hide yes)
			(effects
				(font
					(size 0.7874 0.5842)
					(thickness 0.127)
				)
				(justify mirror)
			)
		)
		(duplicate_pad_numbers_are_jumpers no)
		(fp_line
			(start 0.970026 0.4699)
			(end 0.970026 -0.4699)
			(stroke
				(width 0.1)
				(type default)
			)
			(layer "B.SilkS")
		)
		(fp_line
			(start 0.970026 -0.4699)
			(end -0.970026 -0.4699)
			(stroke
				(width 0.1)
				(type default)
			)
			(layer "B.SilkS")
		)
		(fp_line
			(start -0.970026 0.4699)
			(end 0.970026 0.4699)
			(stroke
				(width 0.1)
				(type default)
			)
			(layer "B.SilkS")
		)
		(fp_line
			(start -0.970026 -0.4699)
			(end -0.970026 0.4699)
			(stroke
				(width 0.1)
				(type default)
			)
			(layer "B.SilkS")
		)
		(fp_poly
			(pts
				(xy 0.970026 0.4699) (xy -0.970026 0.4699) (xy -0.970026 -0.4699) (xy 0.970026 -0.4699)
			)
			(stroke
				(width 0)
				(type default)
			)
			(fill no)
			(layer "B.CrtYd")
		)
		(fp_line
			(start 0.508 0.3048)
			(end 0.508 -0.3048)
			(stroke
				(width 0.1)
				(type default)
			)
			(layer "B.Fab")
		)
		(fp_line
			(start 0.508 -0.3048)
			(end -0.508 -0.3048)
			(stroke
				(width 0.1)
				(type default)
			)
			(layer "B.Fab")
		)
		(fp_line
			(start -0.508 0.3048)
			(end 0.508 0.3048)
			(stroke
				(width 0.1)
				(type default)
			)
			(layer "B.Fab")
		)
		(fp_line
			(start -0.508 -0.3048)
			(end -0.508 0.3048)
			(stroke
				(width 0.1)
				(type default)
			)
			(layer "B.Fab")
		)
		(pad "1" smd circle
			(at 0.500126 0)
			(size 0.635 0.635)
			(layers "B.Cu" "B.Mask" "B.Paste")
			(net "XP1R0V_FPGA_MGTAVCC")
		)
		(pad "2" smd circle
			(at -0.500126 0)
			(size 0.635 0.635)
			(layers "B.Cu" "B.Mask" "B.Paste")
			(net "SG")
		)
	)
	(footprint ""
		(layer "B.Cu")
		(at 36.703 -103.886 180)
		(property "Reference" "R50"
			(at 4.064 -0.16637 0)
			(unlocked yes)
			(layer "B.SilkS")
			(effects
				(font
					(size 0.7874 0.5842)
					(thickness 0.1524)
				)
				(justify mirror)
			)
		)
		(property "Value" "VAL*"
			(at 0.0254 2.524506 180)
			(unlocked yes)
			(layer "B.Fab")
			(hide yes)
			(effects
				(font
					(size 0.7874 0.5842)
					(thickness 0.1524)
				)
				(justify mirror)
			)
		)
		(property "Device Type" "RESISTOR-G156-100R0-J0,0OHM,-"
			(at 0 1.610106 180)
			(unlocked yes)
			(layer "B.Fab")
			(hide yes)
			(effects
				(font
					(size 0.7874 0.5842)
					(thickness 0.1524)
				)
				(justify mirror)
			)
		)
		(property "User Part Number" "PARTNUM*"
			(at 0.0254 4.505706 180)
			(unlocked yes)
			(layer "Cmts.User")
			(hide yes)
			(effects
				(font
					(size 0.7874 0.5842)
					(thickness 0.1524)
				)
				(justify mirror)
			)
		)
		(property "Tolerance" "TOL*"
			(at 0.0254 3.464306 180)
			(unlocked yes)
			(layer "Cmts.User")
			(hide yes)
			(effects
				(font
					(size 0.7874 0.5842)
					(thickness 0.1524)
				)
				(justify mirror)
			)
		)
		(duplicate_pad_numbers_are_jumpers no)
		(fp_line
			(start 1.3208 0.7112)
			(end 1.3208 -0.7112)
			(stroke
				(width 0.1)
				(type default)
			)
			(layer "B.SilkS")
		)
		(fp_line
			(start 1.3208 -0.7112)
			(end -1.3208 -0.7112)
			(stroke
				(width 0.1)
				(type default)
			)
			(layer "B.SilkS")
		)
		(fp_line
			(start -1.3208 0.7112)
			(end 1.3208 0.7112)
			(stroke
				(width 0.1)
				(type default)
			)
			(layer "B.SilkS")
		)
		(fp_line
			(start -1.3208 -0.7112)
			(end -1.3208 0.7112)
			(stroke
				(width 0.1)
				(type default)
			)
			(layer "B.SilkS")
		)
		(fp_rect
			(start -1.3208 0.7112)
			(end 1.3208 -0.7112)
			(stroke
				(width 0)
				(type default)
			)
			(fill no)
			(layer "B.CrtYd")
		)
		(fp_line
			(start 0.8128 0.4572)
			(end 0.8128 -0.4572)
			(stroke
				(width 0.1)
				(type default)
			)
			(layer "B.Fab")
		)
		(fp_line
			(start 0.8128 -0.4572)
			(end -0.8128 -0.4572)
			(stroke
				(width 0.1)
				(type default)
			)
			(layer "B.Fab")
		)
		(fp_line
			(start -0.8128 0.4572)
			(end 0.8128 0.4572)
			(stroke
				(width 0.1)
				(type default)
			)
			(layer "B.Fab")
		)
		(fp_line
			(start -0.8128 -0.4572)
			(end -0.8128 0.4572)
			(stroke
				(width 0.1)
				(type default)
			)
			(layer "B.Fab")
		)
		(pad "1" smd rect
			(at 0.6858 0)
			(size 0.762 0.8636)
			(layers "B.Cu" "B.Mask" "B.Paste")
			(net "XP5R0V_AGND")
		)
		(pad "2" smd rect
			(at -0.6858 0)
			(size 0.762 0.8636)
			(layers "B.Cu" "B.Mask" "B.Paste")
			(net "XP5R0V_FB_R_TO_AGND")
		)
		(zone
			(layer "B.Cu")
			(hatch none 0.5)
			(connect_pads
				(clearance 0)
			)
			(min_thickness 0.25)
			(keepout
				(tracks allowed)
				(vias not_allowed)
				(pads allowed)
				(copperpour not_allowed)
				(footprints allowed)
			)
			(placement
				(enabled no)
				(sheetname "")
			)
			(fill
				(thermal_gap 0.5)
				(thermal_bridge_width 0.5)
				(island_removal_mode 0)
			)
			(polygon
				(pts
					(xy 36.8554 -104.3432) (xy 36.5506 -104.3432) (xy 36.5506 -103.4288) (xy 36.8554 -103.4288)
				)
			)
		)
	)
)
